(kicad_pcb
	(version 20260206)
	(generator "pcbnew")
	(generator_version "10.0")
	(general
		(thickness 1.6)
		(legacy_teardrops no)
	)
	(paper "A4")
	(title_block
		(title "baseboard — 13948-1b.1110WZS1818.brd")
		(comment 1 "Honey Badger (Wiwynn) / footprints 676-682 of 2523")
	)
	(layers
		(0 "F.Cu" signal "TOP")
		(4 "In1.Cu" signal "L2GND")
		(6 "In2.Cu" signal "L3")
		(8 "In3.Cu" signal "L4VCC")
		(10 "In4.Cu" signal "L5VCC")
		(12 "In5.Cu" signal "L6")
		(14 "In6.Cu" signal "L7GND")
		(2 "B.Cu" signal "BOTTOM")
		(9 "F.Adhes" user "F.Adhesive")
		(11 "B.Adhes" user "B.Adhesive")
		(13 "F.Paste" user "Package Geometry/Pastemask Top")
		(15 "B.Paste" user "Package Geometry/Pastemask Bottom")
		(5 "F.SilkS" user "Ref Des/Silkscreen Top")
		(7 "B.SilkS" user "Ref Des/Silkscreen Bottom")
		(1 "F.Mask" user "Board Geometry/Soldermask Top")
		(3 "B.Mask" user "Board Geometry/Soldermask Bottom")
		(17 "Dwgs.User" user "User.Drawings")
		(19 "Cmts.User" user "User.Comments")
		(21 "Eco1.User" user "User.Eco1")
		(23 "Eco2.User" user "User.Eco2")
		(25 "Edge.Cuts" user "Board Geometry/Outline")
		(27 "Margin" user)
		(31 "F.CrtYd" user "Package Geometry/Place Bound Top")
		(29 "B.CrtYd" user "Package Geometry/Place Bound Bottom")
		(35 "F.Fab" user "Ref Des/Assembly Top")
		(33 "B.Fab" user "Ref Des/Assembly Bottom")
	)
	(footprint ""
		(layer "F.Cu")
		(at 283.21 -207.518 90)
		(property "Reference" "C272"
			(at 0 0 90)
			(layer "F.SilkS")
			(hide yes)
			(effects
				(font
					(size 1.27 1.27)
				)
			)
		)
		(property "Value" "SCD1U16V2KX-3GP"
			(at 1.1811 -2.7051 90)
			(unlocked yes)
			(layer "F.Fab")
			(hide yes)
			(effects
				(font
					(size 1.016 1.016)
					(thickness 0.1524)
				)
			)
		)
		(property "Device Type" "C402H22"
			(at 1.1811 -4.2291 90)
			(unlocked yes)
			(layer "F.Fab")
			(hide yes)
			(effects
				(font
					(size 1.016 1.016)
					(thickness 0.1524)
				)
			)
		)
		(duplicate_pad_numbers_are_jumpers no)
		(fp_rect
			(start -0.4318 0.9525)
			(end 0.4318 -0.9525)
			(stroke
				(width 0)
				(type default)
			)
			(fill no)
			(layer "F.CrtYd")
		)
		(fp_rect
			(start -0.4318 0.9525)
			(end 0.4318 -0.9525)
			(stroke
				(width 0)
				(type default)
			)
			(fill no)
			(layer "F.Fab")
		)
		(pad "1" smd custom
			(at 0 -0.4445 90)
			(size 0.1524 0.1524)
			(layers "F.Cu" "F.Mask" "F.Paste")
			(net "P3V3_STBY")
			(options
				(clearance outline)
				(anchor circle)
			)
			(primitives
				(gr_poly
					(pts
						(arc
							(start 0.3048 -0.2032)
							(mid 0.275042 -0.275042)
							(end 0.2032 -0.3048)
						)
						(arc
							(start -0.2032 -0.3048)
							(mid -0.275042 -0.275042)
							(end -0.3048 -0.2032)
						)
						(arc
							(start -0.3048 0.2032)
							(mid -0.275042 0.275042)
							(end -0.2032 0.3048)
						)
						(arc
							(start 0.2032 0.3048)
							(mid 0.275042 0.275042)
							(end 0.3048 0.2032)
						)
					)
					(width 0)
					(fill yes)
				)
			)
		)
		(pad "2" smd custom
			(at 0 0.4445 90)
			(size 0.1524 0.1524)
			(layers "F.Cu" "F.Mask" "F.Paste")
			(net "GND")
			(options
				(clearance outline)
				(anchor circle)
			)
			(primitives
				(gr_poly
					(pts
						(arc
							(start 0.3048 -0.2032)
							(mid 0.275042 -0.275042)
							(end 0.2032 -0.3048)
						)
						(arc
							(start -0.2032 -0.3048)
							(mid -0.275042 -0.275042)
							(end -0.3048 -0.2032)
						)
						(arc
							(start -0.3048 0.2032)
							(mid -0.275042 0.275042)
							(end -0.2032 0.3048)
						)
						(arc
							(start 0.2032 0.3048)
							(mid 0.275042 0.275042)
							(end 0.3048 0.2032)
						)
					)
					(width 0)
					(fill yes)
				)
			)
		)
	)
	(footprint ""
		(layer "F.Cu")
		(at 120.15597 -114.3 180)
		(property "Reference" "SC1069"
			(at 0 0 180)
			(layer "F.SilkS")
			(hide yes)
			(effects
				(font
					(size 1.27 1.27)
				)
			)
		)
		(property "Value" "SCD01U10V1KX-GP"
			(at -2.8321 -1.7399 180)
			(unlocked yes)
			(layer "F.Fab")
			(hide yes)
			(effects
				(font
					(size 1.016 1.016)
					(thickness 0.1524)
				)
			)
		)
		(property "Device Type" "C0201H13"
			(at -2.8321 -3.2639 180)
			(unlocked yes)
			(layer "F.Fab")
			(hide yes)
			(effects
				(font
					(size 1.016 1.016)
					(thickness 0.1524)
				)
			)
		)
		(duplicate_pad_numbers_are_jumpers no)
		(fp_rect
			(start -0.2794 0.6477)
			(end 0.2794 -0.6477)
			(stroke
				(width 0)
				(type default)
			)
			(fill no)
			(layer "F.CrtYd")
		)
		(fp_rect
			(start -0.2794 0.6477)
			(end 0.2794 -0.6477)
			(stroke
				(width 0)
				(type default)
			)
			(fill no)
			(layer "F.Fab")
		)
		(pad "1" smd custom
			(at 0 -0.2794 180)
			(size 0.0762 0.0762)
			(layers "F.Cu" "F.Mask" "F.Paste")
			(net "SAS_HDD_TX1_P")
			(options
				(clearance outline)
				(anchor circle)
			)
			(primitives
				(gr_poly
					(pts
						(arc
							(start 0.1524 -0.127)
							(mid 0.137521 -0.162921)
							(end 0.1016 -0.1778)
						)
						(arc
							(start -0.1016 -0.1778)
							(mid -0.137521 -0.162921)
							(end -0.1524 -0.127)
						)
						(arc
							(start -0.1524 0.127)
							(mid -0.137521 0.162921)
							(end -0.1016 0.1778)
						)
						(arc
							(start 0.1016 0.1778)
							(mid 0.137521 0.162921)
							(end 0.1524 0.127)
						)
					)
					(width 0)
					(fill yes)
				)
			)
		)
		(pad "2" smd custom
			(at 0 0.2794 180)
			(size 0.0762 0.0762)
			(layers "F.Cu" "F.Mask" "F.Paste")
			(net "SAS_EXP_GF_TX_DP5")
			(options
				(clearance outline)
				(anchor circle)
			)
			(primitives
				(gr_poly
					(pts
						(arc
							(start 0.1524 -0.127)
							(mid 0.137521 -0.162921)
							(end 0.1016 -0.1778)
						)
						(arc
							(start -0.1016 -0.1778)
							(mid -0.137521 -0.162921)
							(end -0.1524 -0.127)
						)
						(arc
							(start -0.1524 0.127)
							(mid -0.137521 0.162921)
							(end -0.1016 0.1778)
						)
						(arc
							(start 0.1016 0.1778)
							(mid 0.137521 0.162921)
							(end 0.1524 0.127)
						)
					)
					(width 0)
					(fill yes)
				)
			)
		)
	)
	(footprint ""
		(layer "F.Cu")
		(at 165.703504 -24.184356 180)
		(property "Reference" "R416"
			(at 0 0 180)
			(layer "F.SilkS")
			(hide yes)
			(effects
				(font
					(size 1.27 1.27)
				)
			)
		)
		(property "Value" "0R2J-2-GP"
			(at 0.064008 -3.993896 180)
			(unlocked yes)
			(layer "F.Fab")
			(hide yes)
			(effects
				(font
					(size 1.016 1.016)
					(thickness 0.1524)
				)
			)
		)
		(property "Device Type" "R402H16"
			(at 0.064008 -5.517896 180)
			(unlocked yes)
			(layer "F.Fab")
			(hide yes)
			(effects
				(font
					(size 1.016 1.016)
					(thickness 0.1524)
				)
			)
		)
		(duplicate_pad_numbers_are_jumpers no)
		(fp_line
			(start 0.508 -0.9398)
			(end -0.508 -0.9398)
			(stroke
				(width 0.1524)
				(type default)
			)
			(layer "F.SilkS")
		)
		(fp_line
			(start -0.508 -0.9398)
			(end -0.508 0.9398)
			(stroke
				(width 0.1524)
				(type default)
			)
			(layer "F.SilkS")
		)
		(fp_rect
			(start -0.508 0.9398)
			(end 0.508 -0.9398)
			(stroke
				(width 0)
				(type default)
			)
			(fill no)
			(layer "F.CrtYd")
		)
		(fp_rect
			(start -0.508 0.9398)
			(end 0.508 -0.9398)
			(stroke
				(width 0)
				(type default)
			)
			(fill no)
			(layer "F.Fab")
		)
		(pad "1" smd custom
			(at 0 -0.4445 180)
			(size 0.1397 0.1397)
			(layers "F.Cu" "F.Mask" "F.Paste")
			(net "TP_LAN_4")
			(options
				(clearance outline)
				(anchor circle)
			)
			(primitives
				(gr_poly
					(pts
						(arc
							(start -0.1778 -0.2794)
							(mid -0.249642 -0.249642)
							(end -0.2794 -0.1778)
						)
						(arc
							(start -0.2794 0.1778)
							(mid -0.249642 0.249642)
							(end -0.1778 0.2794)
						)
						(arc
							(start 0.1778 0.2794)
							(mid 0.249642 0.249642)
							(end 0.2794 0.1778)
						)
						(arc
							(start 0.2794 -0.1778)
							(mid 0.249642 -0.249642)
							(end 0.1778 -0.2794)
						)
					)
					(width 0)
					(fill yes)
				)
			)
		)
		(pad "2" smd custom
			(at 0 0.4445 180)
			(size 0.1397 0.1397)
			(layers "F.Cu" "F.Mask" "F.Paste")
			(net "GND")
			(options
				(clearance outline)
				(anchor circle)
			)
			(primitives
				(gr_poly
					(pts
						(arc
							(start -0.1778 -0.2794)
							(mid -0.249642 -0.249642)
							(end -0.2794 -0.1778)
						)
						(arc
							(start -0.2794 0.1778)
							(mid -0.249642 0.249642)
							(end -0.1778 0.2794)
						)
						(arc
							(start 0.1778 0.2794)
							(mid 0.249642 0.249642)
							(end 0.2794 0.1778)
						)
						(arc
							(start 0.2794 -0.1778)
							(mid 0.249642 -0.249642)
							(end 0.1778 -0.2794)
						)
					)
					(width 0)
					(fill yes)
				)
			)
		)
	)
	(footprint ""
		(layer "F.Cu")
		(at 60.706 -109.474 -90)
		(property "Reference" "SR823"
			(at 0 0 270)
			(layer "F.SilkS")
			(hide yes)
			(effects
				(font
					(size 1.27 1.27)
				)
			)
		)
		(property "Value" "4K75R2F-1-GP"
			(at 0.064008 -3.993896 270)
			(unlocked yes)
			(layer "F.Fab")
			(hide yes)
			(effects
				(font
					(size 1.016 1.016)
					(thickness 0.1524)
				)
			)
		)
		(property "Device Type" "R402H16"
			(at 0.064008 -5.517896 270)
			(unlocked yes)
			(layer "F.Fab")
			(hide yes)
			(effects
				(font
					(size 1.016 1.016)
					(thickness 0.1524)
				)
			)
		)
		(duplicate_pad_numbers_are_jumpers no)
		(fp_line
			(start -0.508 -0.9398)
			(end -0.508 0.9398)
			(stroke
				(width 0.1524)
				(type default)
			)
			(layer "F.SilkS")
		)
		(fp_line
			(start 0.508 -0.9398)
			(end -0.508 -0.9398)
			(stroke
				(width 0.1524)
				(type default)
			)
			(layer "F.SilkS")
		)
		(fp_rect
			(start -0.508 0.9398)
			(end 0.508 -0.9398)
			(stroke
				(width 0)
				(type default)
			)
			(fill no)
			(layer "F.CrtYd")
		)
		(fp_rect
			(start -0.508 0.9398)
			(end 0.508 -0.9398)
			(stroke
				(width 0)
				(type default)
			)
			(fill no)
			(layer "F.Fab")
		)
		(pad "1" smd custom
			(at 0 -0.4445 270)
			(size 0.1397 0.1397)
			(layers "F.Cu" "F.Mask" "F.Paste")
			(net "EXP_FW_DET_BOARD_VER_0")
			(options
				(clearance outline)
				(anchor circle)
			)
			(primitives
				(gr_poly
					(pts
						(arc
							(start -0.1778 -0.2794)
							(mid -0.249642 -0.249642)
							(end -0.2794 -0.1778)
						)
						(arc
							(start -0.2794 0.1778)
							(mid -0.249642 0.249642)
							(end -0.1778 0.2794)
						)
						(arc
							(start 0.1778 0.2794)
							(mid 0.249642 0.249642)
							(end 0.2794 0.1778)
						)
						(arc
							(start 0.2794 -0.1778)
							(mid 0.249642 -0.249642)
							(end 0.1778 -0.2794)
						)
					)
					(width 0)
					(fill yes)
				)
			)
		)
		(pad "2" smd custom
			(at 0 0.4445 270)
			(size 0.1397 0.1397)
			(layers "F.Cu" "F.Mask" "F.Paste")
			(net "GND")
			(options
				(clearance outline)
				(anchor circle)
			)
			(primitives
				(gr_poly
					(pts
						(arc
							(start -0.1778 -0.2794)
							(mid -0.249642 -0.249642)
							(end -0.2794 -0.1778)
						)
						(arc
							(start -0.2794 0.1778)
							(mid -0.249642 0.249642)
							(end -0.1778 0.2794)
						)
						(arc
							(start 0.1778 0.2794)
							(mid 0.249642 0.249642)
							(end 0.2794 0.1778)
						)
						(arc
							(start 0.2794 -0.1778)
							(mid 0.249642 -0.249642)
							(end 0.1778 -0.2794)
						)
					)
					(width 0)
					(fill yes)
				)
			)
		)
	)
	(footprint ""
		(layer "F.Cu")
		(at 138.176 -38.862 180)
		(property "Reference" "SR693"
			(at 0 0 180)
			(layer "F.SilkS")
			(hide yes)
			(effects
				(font
					(size 1.27 1.27)
				)
			)
		)
		(property "Value" "10KR2F-2-GP"
			(at 0.064008 -3.993896 180)
			(unlocked yes)
			(layer "F.Fab")
			(hide yes)
			(effects
				(font
					(size 1.016 1.016)
					(thickness 0.1524)
				)
			)
		)
		(property "Device Type" "R402H16"
			(at 0.064008 -5.517896 180)
			(unlocked yes)
			(layer "F.Fab")
			(hide yes)
			(effects
				(font
					(size 1.016 1.016)
					(thickness 0.1524)
				)
			)
		)
		(duplicate_pad_numbers_are_jumpers no)
		(fp_line
			(start 0.508 -0.9398)
			(end -0.508 -0.9398)
			(stroke
				(width 0.1524)
				(type default)
			)
			(layer "F.SilkS")
		)
		(fp_line
			(start -0.508 -0.9398)
			(end -0.508 0.9398)
			(stroke
				(width 0.1524)
				(type default)
			)
			(layer "F.SilkS")
		)
		(fp_rect
			(start -0.508 0.9398)
			(end 0.508 -0.9398)
			(stroke
				(width 0)
				(type default)
			)
			(fill no)
			(layer "F.CrtYd")
		)
		(fp_rect
			(start -0.508 0.9398)
			(end 0.508 -0.9398)
			(stroke
				(width 0)
				(type default)
			)
			(fill no)
			(layer "F.Fab")
		)
		(pad "1" smd custom
			(at 0 -0.4445 180)
			(size 0.1397 0.1397)
			(layers "F.Cu" "F.Mask" "F.Paste")
			(net "P1V8_C")
			(options
				(clearance outline)
				(anchor circle)
			)
			(primitives
				(gr_poly
					(pts
						(arc
							(start -0.1778 -0.2794)
							(mid -0.249642 -0.249642)
							(end -0.2794 -0.1778)
						)
						(arc
							(start -0.2794 0.1778)
							(mid -0.249642 0.249642)
							(end -0.1778 0.2794)
						)
						(arc
							(start 0.1778 0.2794)
							(mid 0.249642 0.249642)
							(end 0.2794 0.1778)
						)
						(arc
							(start 0.2794 -0.1778)
							(mid 0.249642 -0.249642)
							(end 0.1778 -0.2794)
						)
					)
					(width 0)
					(fill yes)
				)
			)
		)
		(pad "2" smd custom
			(at 0 0.4445 180)
			(size 0.1397 0.1397)
			(layers "F.Cu" "F.Mask" "F.Paste")
			(net "XM_ADDR_23")
			(options
				(clearance outline)
				(anchor circle)
			)
			(primitives
				(gr_poly
					(pts
						(arc
							(start -0.1778 -0.2794)
							(mid -0.249642 -0.249642)
							(end -0.2794 -0.1778)
						)
						(arc
							(start -0.2794 0.1778)
							(mid -0.249642 0.249642)
							(end -0.1778 0.2794)
						)
						(arc
							(start 0.1778 0.2794)
							(mid 0.249642 0.249642)
							(end 0.2794 0.1778)
						)
						(arc
							(start 0.2794 -0.1778)
							(mid 0.249642 -0.249642)
							(end 0.1778 -0.2794)
						)
					)
					(width 0)
					(fill yes)
				)
			)
		)
	)
	(footprint ""
		(layer "F.Cu")
		(at 235.966 -13.081 90)
		(property "Reference" "C269"
			(at 0 0 90)
			(layer "F.SilkS")
			(hide yes)
			(effects
				(font
					(size 1.27 1.27)
				)
			)
		)
		(property "Value" "SCD1U16V2KX-3GP"
			(at 1.1811 -2.7051 90)
			(unlocked yes)
			(layer "F.Fab")
			(hide yes)
			(effects
				(font
					(size 1.016 1.016)
					(thickness 0.1524)
				)
			)
		)
		(property "Device Type" "C402H22"
			(at 1.1811 -4.2291 90)
			(unlocked yes)
			(layer "F.Fab")
			(hide yes)
			(effects
				(font
					(size 1.016 1.016)
					(thickness 0.1524)
				)
			)
		)
		(duplicate_pad_numbers_are_jumpers no)
		(fp_rect
			(start -0.4318 0.9525)
			(end 0.4318 -0.9525)
			(stroke
				(width 0)
				(type default)
			)
			(fill no)
			(layer "F.CrtYd")
		)
		(fp_rect
			(start -0.4318 0.9525)
			(end 0.4318 -0.9525)
			(stroke
				(width 0)
				(type default)
			)
			(fill no)
			(layer "F.Fab")
		)
		(pad "1" smd custom
			(at 0 -0.4445 90)
			(size 0.1524 0.1524)
			(layers "F.Cu" "F.Mask" "F.Paste")
			(net "P3V3_STBY")
			(options
				(clearance outline)
				(anchor circle)
			)
			(primitives
				(gr_poly
					(pts
						(arc
							(start 0.3048 -0.2032)
							(mid 0.275042 -0.275042)
							(end 0.2032 -0.3048)
						)
						(arc
							(start -0.2032 -0.3048)
							(mid -0.275042 -0.275042)
							(end -0.3048 -0.2032)
						)
						(arc
							(start -0.3048 0.2032)
							(mid -0.275042 0.275042)
							(end -0.2032 0.3048)
						)
						(arc
							(start 0.2032 0.3048)
							(mid 0.275042 0.275042)
							(end 0.3048 0.2032)
						)
					)
					(width 0)
					(fill yes)
				)
			)
		)
		(pad "2" smd custom
			(at 0 0.4445 90)
			(size 0.1524 0.1524)
			(layers "F.Cu" "F.Mask" "F.Paste")
			(net "GND")
			(options
				(clearance outline)
				(anchor circle)
			)
			(primitives
				(gr_poly
					(pts
						(arc
							(start 0.3048 -0.2032)
							(mid 0.275042 -0.275042)
							(end 0.2032 -0.3048)
						)
						(arc
							(start -0.2032 -0.3048)
							(mid -0.275042 -0.275042)
							(end -0.3048 -0.2032)
						)
						(arc
							(start -0.3048 0.2032)
							(mid -0.275042 0.275042)
							(end -0.2032 0.3048)
						)
						(arc
							(start 0.2032 0.3048)
							(mid 0.275042 0.275042)
							(end 0.3048 0.2032)
						)
					)
					(width 0)
					(fill yes)
				)
			)
		)
	)
	(footprint ""
		(layer "F.Cu")
		(at 310.896 -183.515 90)
		(property "Reference" "R800"
			(at 0 0 90)
			(layer "F.SilkS")
			(hide yes)
			(effects
				(font
					(size 1.27 1.27)
				)
			)
		)
		(property "Value" "0R2J-2-GP"
			(at 0.064008 -3.993896 90)
			(unlocked yes)
			(layer "F.Fab")
			(hide yes)
			(effects
				(font
					(size 1.016 1.016)
					(thickness 0.1524)
				)
			)
		)
		(property "Device Type" "R402H16"
			(at 0.064008 -5.517896 90)
			(unlocked yes)
			(layer "F.Fab")
			(hide yes)
			(effects
				(font
					(size 1.016 1.016)
					(thickness 0.1524)
				)
			)
		)
		(duplicate_pad_numbers_are_jumpers no)
		(fp_line
			(start 0.508 -0.9398)
			(end -0.508 -0.9398)
			(stroke
				(width 0.1524)
				(type default)
			)
			(layer "F.SilkS")
		)
		(fp_line
			(start -0.508 -0.9398)
			(end -0.508 0.9398)
			(stroke
				(width 0.1524)
				(type default)
			)
			(layer "F.SilkS")
		)
		(fp_rect
			(start -0.508 0.9398)
			(end 0.508 -0.9398)
			(stroke
				(width 0)
				(type default)
			)
			(fill no)
			(layer "F.CrtYd")
		)
		(fp_rect
			(start -0.508 0.9398)
			(end 0.508 -0.9398)
			(stroke
				(width 0)
				(type default)
			)
			(fill no)
			(layer "F.Fab")
		)
		(pad "1" smd custom
			(at 0 -0.4445 90)
			(size 0.1397 0.1397)
			(layers "F.Cu" "F.Mask" "F.Paste")
			(net "BMC0_LED_DR_R_LED1")
			(options
				(clearance outline)
				(anchor circle)
			)
			(primitives
				(gr_poly
					(pts
						(arc
							(start -0.1778 -0.2794)
							(mid -0.249642 -0.249642)
							(end -0.2794 -0.1778)
						)
						(arc
							(start -0.2794 0.1778)
							(mid -0.249642 0.249642)
							(end -0.1778 0.2794)
						)
						(arc
							(start 0.1778 0.2794)
							(mid 0.249642 0.249642)
							(end 0.2794 0.1778)
						)
						(arc
							(start 0.2794 -0.1778)
							(mid 0.249642 -0.249642)
							(end 0.1778 -0.2794)
						)
					)
					(width 0)
					(fill yes)
				)
			)
		)
		(pad "2" smd custom
			(at 0 0.4445 90)
			(size 0.1397 0.1397)
			(layers "F.Cu" "F.Mask" "F.Paste")
			(net "LED_DR_LED1")
			(options
				(clearance outline)
				(anchor circle)
			)
			(primitives
				(gr_poly
					(pts
						(arc
							(start -0.1778 -0.2794)
							(mid -0.249642 -0.249642)
							(end -0.2794 -0.1778)
						)
						(arc
							(start -0.2794 0.1778)
							(mid -0.249642 0.249642)
							(end -0.1778 0.2794)
						)
						(arc
							(start 0.1778 0.2794)
							(mid 0.249642 0.249642)
							(end 0.2794 0.1778)
						)
						(arc
							(start 0.2794 -0.1778)
							(mid 0.249642 -0.249642)
							(end 0.1778 -0.2794)
						)
					)
					(width 0)
					(fill yes)
				)
			)
		)
	)
)
